# S9S_MB_2U (Grand Teton) — schematic netlist excerpt (pin names and nets, part order shuffled) for the footprints in the layout excerpt that follows; sources: Cadence DE-HDL packaged netlist, KiCad conversion of 03242023_DA0F0TMBIJ0_F0T_Motherboard_J_brd_V01_OCP.brd

C2370  Q_CAP  0.1UF 25V 10% EMPTY  pkg 0402  page 224 : A = P3V3_AUX ; B = GND
R3352  Q_RES  0 5% CHIP  pkg 0402LF  page 207 : A = CLK_100M_GPU_1_R_DP ; B = CLK_100M_GPU_1_DP

(kicad_pcb
	(version 20260206)
	(generator "pcbnew")
	(generator_version "10.0")
	(general
		(thickness 1.6)
		(legacy_teardrops no)
	)
	(paper "A4")
	(title_block
		(title "03242023_DA0F0TMBIJ0_F0T_Motherboard_J_brd_V01_OCP.brd")
		(comment 1 "Grand Teton / footprints 2891-2893 of 6105")
	)
	(layers
		(0 "F.Cu" signal "TOP")
		(4 "In1.Cu" signal "GND")
		(6 "In2.Cu" signal "IN1")
		(8 "In3.Cu" signal "GND1")
		(10 "In4.Cu" signal "IN2")
		(12 "In5.Cu" signal "GND2")
		(14 "In6.Cu" signal "IN3")
		(16 "In7.Cu" signal "GND3")
		(18 "In8.Cu" signal "VCC")
		(20 "In9.Cu" signal "VCC1")
		(22 "In10.Cu" signal "GND4")
		(24 "In11.Cu" signal "IN4")
		(26 "In12.Cu" signal "GND5")
		(28 "In13.Cu" signal "IN5")
		(30 "In14.Cu" signal "GND6")
		(32 "In15.Cu" signal "IN6")
		(34 "In16.Cu" signal "GND7")
		(2 "B.Cu" signal "BOTTOM")
		(9 "F.Adhes" user "F.Adhesive")
		(11 "B.Adhes" user "B.Adhesive")
		(13 "F.Paste" user "Package Geometry/Pastemask Top")
		(15 "B.Paste" user "Package Geometry/Pastemask Bottom")
		(5 "F.SilkS" user "Ref Des/Silkscreen Top")
		(7 "B.SilkS" user "Ref Des/Silkscreen Bottom")
		(1 "F.Mask" user "Board Geometry/Soldermask Top")
		(3 "B.Mask" user "Board Geometry/Soldermask Bottom")
		(17 "Dwgs.User" user "User.Drawings")
		(19 "Cmts.User" user "User.Comments")
		(21 "Eco1.User" user "User.Eco1")
		(23 "Eco2.User" user "User.Eco2")
		(25 "Edge.Cuts" user "Board Geometry/Outline")
		(27 "Margin" user)
		(31 "F.CrtYd" user "Package Geometry/Place Bound Top")
		(29 "B.CrtYd" user "Package Geometry/Place Bound Bottom")
		(35 "F.Fab" user "Ref Des/Assembly Top")
		(33 "B.Fab" user "Ref Des/Assembly Bottom")
	)
	(footprint ""
		(layer "F.Cu")
		(at 208.49336 -121.1072 180)
		(property "Reference" "C2370"
			(at 0 0 180)
			(layer "F.SilkS")
			(hide yes)
			(effects
				(font
					(size 1.27 1.27)
				)
			)
		)
		(property "Value" ""
			(at 0 0 180)
			(layer "F.Fab")
			(effects
				(font
					(size 1.27 1.27)
				)
			)
		)
		(duplicate_pad_numbers_are_jumpers no)
		(fp_line
			(start 0.7874 0.4064)
			(end -0.7874 0.4064)
			(stroke
				(width 0.1524)
				(type default)
			)
			(layer "F.SilkS")
		)
		(fp_line
			(start 0.7874 -0.4064)
			(end 0.7874 0.4064)
			(stroke
				(width 0.1524)
				(type default)
			)
			(layer "F.SilkS")
		)
		(fp_line
			(start -0.7874 0.4064)
			(end -0.7874 -0.4064)
			(stroke
				(width 0.1524)
				(type default)
			)
			(layer "F.SilkS")
		)
		(fp_line
			(start -0.7874 -0.4064)
			(end 0.7874 -0.4064)
			(stroke
				(width 0.1524)
				(type default)
			)
			(layer "F.SilkS")
		)
		(fp_line
			(start 0.67945 0.3048)
			(end 0.120396 0.3048)
			(stroke
				(width 0.1)
				(type default)
			)
			(layer "F.Fab")
		)
		(fp_line
			(start 0.67945 -0.3048)
			(end 0.67945 0.3048)
			(stroke
				(width 0.1)
				(type default)
			)
			(layer "F.Fab")
		)
		(fp_line
			(start 0.12065 -0.2794)
			(end 0.12065 -0.3048)
			(stroke
				(width 0.1)
				(type default)
			)
			(layer "F.Fab")
		)
		(fp_line
			(start 0.12065 -0.3048)
			(end 0.67945 -0.3048)
			(stroke
				(width 0.1)
				(type default)
			)
			(layer "F.Fab")
		)
		(fp_line
			(start 0.120396 0.3048)
			(end 0.120396 0.2794)
			(stroke
				(width 0.1)
				(type default)
			)
			(layer "F.Fab")
		)
		(fp_line
			(start 0.120396 0.2794)
			(end -0.12065 0.2794)
			(stroke
				(width 0.1)
				(type default)
			)
			(layer "F.Fab")
		)
		(fp_line
			(start -0.12065 0.3048)
			(end -0.67945 0.3048)
			(stroke
				(width 0.1)
				(type default)
			)
			(layer "F.Fab")
		)
		(fp_line
			(start -0.12065 0.2794)
			(end -0.12065 0.3048)
			(stroke
				(width 0.1)
				(type default)
			)
			(layer "F.Fab")
		)
		(fp_line
			(start -0.12065 -0.2794)
			(end 0.12065 -0.2794)
			(stroke
				(width 0.1)
				(type default)
			)
			(layer "F.Fab")
		)
		(fp_line
			(start -0.12065 -0.305054)
			(end -0.12065 -0.2794)
			(stroke
				(width 0.1)
				(type default)
			)
			(layer "F.Fab")
		)
		(fp_line
			(start -0.67945 0.3048)
			(end -0.67945 -0.305054)
			(stroke
				(width 0.1)
				(type default)
			)
			(layer "F.Fab")
		)
		(fp_line
			(start -0.67945 -0.305054)
			(end -0.12065 -0.305054)
			(stroke
				(width 0.1)
				(type default)
			)
			(layer "F.Fab")
		)
		(pad "1" smd circle
			(at -0.40005 0 180)
			(size 0 0)
			(layers "F.Cu" "F.Mask" "F.Paste")
			(net "P3V3_AUX")
		)
		(pad "2" smd circle
			(at 0.40005 0 180)
			(size 0 0)
			(layers "F.Cu" "F.Mask" "F.Paste")
			(net "GND")
		)
	)
	(footprint ""
		(layer "F.Cu")
		(at 282.61818 -137.577068)
		(property "Reference" ""
			(at 0 0 0)
			(layer "F.SilkS")
			(hide yes)
			(effects
				(font
					(size 1.27 1.27)
				)
			)
		)
		(property "Value" ""
			(at 0 0 0)
			(layer "F.Fab")
			(effects
				(font
					(size 1.27 1.27)
				)
			)
		)
		(duplicate_pad_numbers_are_jumpers no)
		(pad "1" smd circle
			(at 0 0)
			(size 0.9906 0.9906)
			(layers "F.Cu" "F.Mask" "F.Paste")
			(net "Net_289")
		)
		(zone
			(layer "F.Cu")
			(hatch none 0.5)
			(connect_pads
				(clearance 0)
			)
			(min_thickness 0.25)
			(keepout
				(tracks not_allowed)
				(vias allowed)
				(pads allowed)
				(copperpour not_allowed)
				(footprints allowed)
			)
			(placement
				(enabled no)
				(sheetname "")
			)
			(fill
				(thermal_gap 0.5)
				(thermal_bridge_width 0.5)
				(island_removal_mode 0)
			)
			(polygon
				(pts
					(arc
						(start 284.24378 -137.577068)
						(mid 280.99258 -137.577068)
						(end 284.24378 -137.577068)
					)
				)
			)
		)
	)
	(footprint ""
		(layer "F.Cu")
		(at 106.70921 -415.757868 180)
		(property "Reference" "R3352"
			(at 0 0 180)
			(layer "F.SilkS")
			(hide yes)
			(effects
				(font
					(size 1.27 1.27)
				)
			)
		)
		(property "Value" ""
			(at 0 0 180)
			(layer "F.Fab")
			(effects
				(font
					(size 1.27 1.27)
				)
			)
		)
		(duplicate_pad_numbers_are_jumpers no)
		(fp_line
			(start 0.7874 0.4064)
			(end -0.7874 0.4064)
			(stroke
				(width 0.1524)
				(type default)
			)
			(layer "F.SilkS")
		)
		(fp_line
			(start 0.7874 -0.1397)
			(end 0.7874 0.4064)
			(stroke
				(width 0.1524)
				(type default)
			)
			(layer "F.SilkS")
		)
		(fp_line
			(start -0.44577 -0.4064)
			(end 0.47371 -0.4064)
			(stroke
				(width 0.1524)
				(type default)
			)
			(layer "F.SilkS")
		)
		(fp_line
			(start -0.7874 0.4064)
			(end -0.7874 -0.16256)
			(stroke
				(width 0.1524)
				(type default)
			)
			(layer "F.SilkS")
		)
		(fp_line
			(start 0.67945 0.3048)
			(end 0.120396 0.3048)
			(stroke
				(width 0.1)
				(type default)
			)
			(layer "F.Fab")
		)
		(fp_line
			(start 0.67945 -0.3048)
			(end 0.67945 0.3048)
			(stroke
				(width 0.1)
				(type default)
			)
			(layer "F.Fab")
		)
		(fp_line
			(start 0.12065 -0.2794)
			(end 0.12065 -0.3048)
			(stroke
				(width 0.1)
				(type default)
			)
			(layer "F.Fab")
		)
		(fp_line
			(start 0.12065 -0.3048)
			(end 0.67945 -0.3048)
			(stroke
				(width 0.1)
				(type default)
			)
			(layer "F.Fab")
		)
		(fp_line
			(start 0.120396 0.3048)
			(end 0.120396 0.2794)
			(stroke
				(width 0.1)
				(type default)
			)
			(layer "F.Fab")
		)
		(fp_line
			(start 0.120396 0.2794)
			(end -0.12065 0.2794)
			(stroke
				(width 0.1)
				(type default)
			)
			(layer "F.Fab")
		)
		(fp_line
			(start -0.12065 0.3048)
			(end -0.67945 0.3048)
			(stroke
				(width 0.1)
				(type default)
			)
			(layer "F.Fab")
		)
		(fp_line
			(start -0.12065 0.2794)
			(end -0.12065 0.3048)
			(stroke
				(width 0.1)
				(type default)
			)
			(layer "F.Fab")
		)
		(fp_line
			(start -0.12065 -0.2794)
			(end 0.12065 -0.2794)
			(stroke
				(width 0.1)
				(type default)
			)
			(layer "F.Fab")
		)
		(fp_line
			(start -0.12065 -0.305054)
			(end -0.12065 -0.2794)
			(stroke
				(width 0.1)
				(type default)
			)
			(layer "F.Fab")
		)
		(fp_line
			(start -0.67945 0.3048)
			(end -0.67945 -0.305054)
			(stroke
				(width 0.1)
				(type default)
			)
			(layer "F.Fab")
		)
		(fp_line
			(start -0.67945 -0.305054)
			(end -0.12065 -0.305054)
			(stroke
				(width 0.1)
				(type default)
			)
			(layer "F.Fab")
		)
		(pad "1" smd circle
			(at -0.40005 0 180)
			(size 0 0)
			(layers "F.Cu" "F.Mask" "F.Paste")
			(net "CLK_100M_GPU_1_R_DP")
		)
		(pad "2" smd circle
			(at 0.40005 0 180)
			(size 0 0)
			(layers "F.Cu" "F.Mask" "F.Paste")
			(net "CLK_100M_GPU_1_DP")
		)
	)
)
